(kicad_pcb
	(version 20260206)
	(generator "pcbnew")
	(generator_version "10.0")
	(general
		(thickness 1.6)
		(legacy_teardrops no)
	)
	(paper "A4")
	(title_block
		(title "12092022_DA0F0TFB6D0_F0T_FAN_BOARD_MP5048_D_brd_v02_OCP.brd")
		(comment 1 "Grand Teton / footprints 148-154 of 924")
	)
	(layers
		(0 "F.Cu" signal "TOP")
		(4 "In1.Cu" signal "GND")
		(6 "In2.Cu" signal "IN1")
		(8 "In3.Cu" signal "IN2")
		(10 "In4.Cu" signal "GND1")
		(2 "B.Cu" signal "BOTTOM")
		(9 "F.Adhes" user "F.Adhesive")
		(11 "B.Adhes" user "B.Adhesive")
		(13 "F.Paste" user "Package Geometry/Pastemask Top")
		(15 "B.Paste" user "Package Geometry/Pastemask Bottom")
		(5 "F.SilkS" user "Ref Des/Silkscreen Top")
		(7 "B.SilkS" user "Ref Des/Silkscreen Bottom")
		(1 "F.Mask" user "Board Geometry/Soldermask Top")
		(3 "B.Mask" user "Board Geometry/Soldermask Bottom")
		(17 "Dwgs.User" user "User.Drawings")
		(19 "Cmts.User" user "User.Comments")
		(21 "Eco1.User" user "User.Eco1")
		(23 "Eco2.User" user "User.Eco2")
		(25 "Edge.Cuts" user "Board Geometry/Outline")
		(27 "Margin" user)
		(31 "F.CrtYd" user "Package Geometry/Place Bound Top")
		(29 "B.CrtYd" user "Package Geometry/Place Bound Bottom")
		(35 "F.Fab" user "Ref Des/Assembly Top")
		(33 "B.Fab" user "Ref Des/Assembly Bottom")
	)
	(footprint ""
		(layer "F.Cu")
		(at 28.829 -102.108 -90)
		(property "Reference" "C2091"
			(at 0 0 270)
			(layer "F.SilkS")
			(hide yes)
			(effects
				(font
					(size 1.27 1.27)
				)
			)
		)
		(property "Value" ""
			(at 0 0 270)
			(layer "F.Fab")
			(effects
				(font
					(size 1.27 1.27)
				)
			)
		)
		(duplicate_pad_numbers_are_jumpers no)
		(fp_line
			(start -0.7874 0.4064)
			(end -0.7874 -0.4064)
			(stroke
				(width 0.1524)
				(type default)
			)
			(layer "F.SilkS")
		)
		(fp_line
			(start 0.7874 0.4064)
			(end -0.7874 0.4064)
			(stroke
				(width 0.1524)
				(type default)
			)
			(layer "F.SilkS")
		)
		(fp_line
			(start -0.7874 -0.4064)
			(end 0.7874 -0.4064)
			(stroke
				(width 0.1524)
				(type default)
			)
			(layer "F.SilkS")
		)
		(fp_line
			(start 0.7874 -0.4064)
			(end 0.7874 0.4064)
			(stroke
				(width 0.1524)
				(type default)
			)
			(layer "F.SilkS")
		)
		(fp_line
			(start -0.67945 0.3048)
			(end -0.67945 -0.305054)
			(stroke
				(width 0.1)
				(type default)
			)
			(layer "F.Fab")
		)
		(fp_line
			(start -0.12065 0.3048)
			(end -0.67945 0.3048)
			(stroke
				(width 0.1)
				(type default)
			)
			(layer "F.Fab")
		)
		(fp_line
			(start 0.120396 0.3048)
			(end 0.120396 0.2794)
			(stroke
				(width 0.1)
				(type default)
			)
			(layer "F.Fab")
		)
		(fp_line
			(start 0.67945 0.3048)
			(end 0.120396 0.3048)
			(stroke
				(width 0.1)
				(type default)
			)
			(layer "F.Fab")
		)
		(fp_line
			(start -0.12065 0.2794)
			(end -0.12065 0.3048)
			(stroke
				(width 0.1)
				(type default)
			)
			(layer "F.Fab")
		)
		(fp_line
			(start 0.120396 0.2794)
			(end -0.12065 0.2794)
			(stroke
				(width 0.1)
				(type default)
			)
			(layer "F.Fab")
		)
		(fp_line
			(start -0.12065 -0.2794)
			(end 0.12065 -0.2794)
			(stroke
				(width 0.1)
				(type default)
			)
			(layer "F.Fab")
		)
		(fp_line
			(start 0.12065 -0.2794)
			(end 0.12065 -0.3048)
			(stroke
				(width 0.1)
				(type default)
			)
			(layer "F.Fab")
		)
		(fp_line
			(start 0.12065 -0.3048)
			(end 0.67945 -0.3048)
			(stroke
				(width 0.1)
				(type default)
			)
			(layer "F.Fab")
		)
		(fp_line
			(start 0.67945 -0.3048)
			(end 0.67945 0.3048)
			(stroke
				(width 0.1)
				(type default)
			)
			(layer "F.Fab")
		)
		(fp_line
			(start -0.67945 -0.305054)
			(end -0.12065 -0.305054)
			(stroke
				(width 0.1)
				(type default)
			)
			(layer "F.Fab")
		)
		(fp_line
			(start -0.12065 -0.305054)
			(end -0.12065 -0.2794)
			(stroke
				(width 0.1)
				(type default)
			)
			(layer "F.Fab")
		)
		(pad "1" smd circle
			(at -0.40005 0 270)
			(size 0 0)
			(layers "F.Cu" "F.Mask" "F.Paste")
			(net "P3V3_AUX")
		)
		(pad "2" smd circle
			(at 0.40005 0 270)
			(size 0 0)
			(layers "F.Cu" "F.Mask" "F.Paste")
			(net "GND")
		)
	)
	(footprint ""
		(layer "F.Cu")
		(at -14.841474 -296.164 180)
		(property "Reference" "J83"
			(at -1.252474 -5.48767 0)
			(unlocked yes)
			(layer "F.SilkS")
			(effects
				(font
					(size 0.7874 0.5842)
					(thickness 0.1524)
				)
				(justify left)
			)
		)
		(property "Value" ""
			(at 0 0 180)
			(layer "F.Fab")
			(effects
				(font
					(size 1.27 1.27)
				)
			)
		)
		(duplicate_pad_numbers_are_jumpers no)
		(fp_line
			(start 3.330702 -4.771136)
			(end 0 4.011168)
			(stroke
				(width 0.1524)
				(type default)
			)
			(layer "F.SilkS")
		)
		(fp_line
			(start 0 4.011168)
			(end -3.330702 -4.771136)
			(stroke
				(width 0.1524)
				(type default)
			)
			(layer "F.SilkS")
		)
		(fp_line
			(start -3.330702 -4.771136)
			(end 3.330702 -4.771136)
			(stroke
				(width 0.1524)
				(type default)
			)
			(layer "F.SilkS")
		)
		(fp_line
			(start 3.330702 -4.771136)
			(end 0 4.011168)
			(stroke
				(width 0.1)
				(type default)
			)
			(layer "F.Fab")
		)
		(fp_line
			(start 0 4.011168)
			(end -3.330702 -4.771136)
			(stroke
				(width 0.1)
				(type default)
			)
			(layer "F.Fab")
		)
		(fp_line
			(start -3.330702 -4.771136)
			(end 3.330702 -4.771136)
			(stroke
				(width 0.1)
				(type default)
			)
			(layer "F.Fab")
		)
		(pad "1" thru_hole circle
			(at 0 0 180)
			(size 2.159 2.159)
			(drill 1.7018)
			(layers "*.Cu" "*.Mask")
			(remove_unused_layers no)
			(net "GND2")
			(clearance 0.0254)
			(thermal_gap 0.0254)
		)
		(pad "2" thru_hole circle
			(at -1.27 -3.348736 180)
			(size 2.159 2.159)
			(drill 1.7018)
			(layers "*.Cu" "*.Mask")
			(remove_unused_layers no)
			(net "TDR_SE_50_OHM_IN1")
			(clearance 0.0254)
			(thermal_gap 0.0254)
		)
		(pad "3" thru_hole circle
			(at 1.27 -3.348736 180)
			(size 2.159 2.159)
			(drill 1.7018)
			(layers "*.Cu" "*.Mask")
			(remove_unused_layers no)
			(net "TDR_SE_50_OHM_IN1")
			(clearance 0.0254)
			(thermal_gap 0.0254)
		)
	)
	(footprint ""
		(layer "F.Cu")
		(at 27.178 -162.941 90)
		(property "Reference" "R5273"
			(at 0 0 90)
			(layer "F.SilkS")
			(hide yes)
			(effects
				(font
					(size 1.27 1.27)
				)
			)
		)
		(property "Value" ""
			(at 0 0 90)
			(layer "F.Fab")
			(effects
				(font
					(size 1.27 1.27)
				)
			)
		)
		(duplicate_pad_numbers_are_jumpers no)
		(fp_line
			(start 0.7874 -0.4064)
			(end 0.7874 0.4064)
			(stroke
				(width 0.1524)
				(type default)
			)
			(layer "F.SilkS")
		)
		(fp_line
			(start -0.7874 -0.4064)
			(end 0.7874 -0.4064)
			(stroke
				(width 0.1524)
				(type default)
			)
			(layer "F.SilkS")
		)
		(fp_line
			(start 0.7874 0.4064)
			(end -0.7874 0.4064)
			(stroke
				(width 0.1524)
				(type default)
			)
			(layer "F.SilkS")
		)
		(fp_line
			(start -0.7874 0.4064)
			(end -0.7874 -0.4064)
			(stroke
				(width 0.1524)
				(type default)
			)
			(layer "F.SilkS")
		)
		(fp_line
			(start -0.12065 -0.305054)
			(end -0.12065 -0.2794)
			(stroke
				(width 0.1)
				(type default)
			)
			(layer "F.Fab")
		)
		(fp_line
			(start -0.67945 -0.305054)
			(end -0.12065 -0.305054)
			(stroke
				(width 0.1)
				(type default)
			)
			(layer "F.Fab")
		)
		(fp_line
			(start 0.67945 -0.3048)
			(end 0.67945 0.3048)
			(stroke
				(width 0.1)
				(type default)
			)
			(layer "F.Fab")
		)
		(fp_line
			(start 0.12065 -0.3048)
			(end 0.67945 -0.3048)
			(stroke
				(width 0.1)
				(type default)
			)
			(layer "F.Fab")
		)
		(fp_line
			(start 0.12065 -0.2794)
			(end 0.12065 -0.3048)
			(stroke
				(width 0.1)
				(type default)
			)
			(layer "F.Fab")
		)
		(fp_line
			(start -0.12065 -0.2794)
			(end 0.12065 -0.2794)
			(stroke
				(width 0.1)
				(type default)
			)
			(layer "F.Fab")
		)
		(fp_line
			(start 0.120396 0.2794)
			(end -0.12065 0.2794)
			(stroke
				(width 0.1)
				(type default)
			)
			(layer "F.Fab")
		)
		(fp_line
			(start -0.12065 0.2794)
			(end -0.12065 0.3048)
			(stroke
				(width 0.1)
				(type default)
			)
			(layer "F.Fab")
		)
		(fp_line
			(start 0.67945 0.3048)
			(end 0.120396 0.3048)
			(stroke
				(width 0.1)
				(type default)
			)
			(layer "F.Fab")
		)
		(fp_line
			(start 0.120396 0.3048)
			(end 0.120396 0.2794)
			(stroke
				(width 0.1)
				(type default)
			)
			(layer "F.Fab")
		)
		(fp_line
			(start -0.12065 0.3048)
			(end -0.67945 0.3048)
			(stroke
				(width 0.1)
				(type default)
			)
			(layer "F.Fab")
		)
		(fp_line
			(start -0.67945 0.3048)
			(end -0.67945 -0.305054)
			(stroke
				(width 0.1)
				(type default)
			)
			(layer "F.Fab")
		)
		(pad "1" smd circle
			(at -0.40005 0 90)
			(size 0 0)
			(layers "F.Cu" "F.Mask" "F.Paste")
			(net "SMB_FAN6_R_SDA")
		)
		(pad "2" smd circle
			(at 0.40005 0 90)
			(size 0 0)
			(layers "F.Cu" "F.Mask" "F.Paste")
			(net "P3V3_AUX")
		)
	)
	(footprint ""
		(layer "F.Cu")
		(at 8.709914 -68.256912)
		(property "Reference" "R5354"
			(at 0 0 0)
			(layer "F.SilkS")
			(hide yes)
			(effects
				(font
					(size 1.27 1.27)
				)
			)
		)
		(property "Value" ""
			(at 0 0 0)
			(layer "F.Fab")
			(effects
				(font
					(size 1.27 1.27)
				)
			)
		)
		(duplicate_pad_numbers_are_jumpers no)
		(fp_line
			(start -0.7874 -0.4064)
			(end 0.7874 -0.4064)
			(stroke
				(width 0.1524)
				(type default)
			)
			(layer "F.SilkS")
		)
		(fp_line
			(start -0.7874 0.4064)
			(end -0.7874 -0.4064)
			(stroke
				(width 0.1524)
				(type default)
			)
			(layer "F.SilkS")
		)
		(fp_line
			(start 0.7874 -0.4064)
			(end 0.7874 0.4064)
			(stroke
				(width 0.1524)
				(type default)
			)
			(layer "F.SilkS")
		)
		(fp_line
			(start 0.7874 0.4064)
			(end -0.7874 0.4064)
			(stroke
				(width 0.1524)
				(type default)
			)
			(layer "F.SilkS")
		)
		(fp_line
			(start -0.67945 -0.305054)
			(end -0.12065 -0.305054)
			(stroke
				(width 0.1)
				(type default)
			)
			(layer "F.Fab")
		)
		(fp_line
			(start -0.67945 0.3048)
			(end -0.67945 -0.305054)
			(stroke
				(width 0.1)
				(type default)
			)
			(layer "F.Fab")
		)
		(fp_line
			(start -0.12065 -0.305054)
			(end -0.12065 -0.2794)
			(stroke
				(width 0.1)
				(type default)
			)
			(layer "F.Fab")
		)
		(fp_line
			(start -0.12065 -0.2794)
			(end 0.12065 -0.2794)
			(stroke
				(width 0.1)
				(type default)
			)
			(layer "F.Fab")
		)
		(fp_line
			(start -0.12065 0.2794)
			(end -0.12065 0.3048)
			(stroke
				(width 0.1)
				(type default)
			)
			(layer "F.Fab")
		)
		(fp_line
			(start -0.12065 0.3048)
			(end -0.67945 0.3048)
			(stroke
				(width 0.1)
				(type default)
			)
			(layer "F.Fab")
		)
		(fp_line
			(start 0.120396 0.2794)
			(end -0.12065 0.2794)
			(stroke
				(width 0.1)
				(type default)
			)
			(layer "F.Fab")
		)
		(fp_line
			(start 0.120396 0.3048)
			(end 0.120396 0.2794)
			(stroke
				(width 0.1)
				(type default)
			)
			(layer "F.Fab")
		)
		(fp_line
			(start 0.12065 -0.3048)
			(end 0.67945 -0.3048)
			(stroke
				(width 0.1)
				(type default)
			)
			(layer "F.Fab")
		)
		(fp_line
			(start 0.12065 -0.2794)
			(end 0.12065 -0.3048)
			(stroke
				(width 0.1)
				(type default)
			)
			(layer "F.Fab")
		)
		(fp_line
			(start 0.67945 -0.3048)
			(end 0.67945 0.3048)
			(stroke
				(width 0.1)
				(type default)
			)
			(layer "F.Fab")
		)
		(fp_line
			(start 0.67945 0.3048)
			(end 0.120396 0.3048)
			(stroke
				(width 0.1)
				(type default)
			)
			(layer "F.Fab")
		)
		(pad "1" smd circle
			(at -0.40005 0)
			(size 0 0)
			(layers "F.Cu" "F.Mask" "F.Paste")
			(net "FAN_4_ON")
		)
		(pad "2" smd circle
			(at 0.40005 0)
			(size 0 0)
			(layers "F.Cu" "F.Mask" "F.Paste")
			(net "P52V_FAN_4_EN")
		)
	)
	(footprint ""
		(layer "F.Cu")
		(at 43.561 -167.513 180)
		(property "Reference" "R5113"
			(at 0 0 180)
			(layer "F.SilkS")
			(hide yes)
			(effects
				(font
					(size 1.27 1.27)
				)
			)
		)
		(property "Value" ""
			(at 0 0 180)
			(layer "F.Fab")
			(effects
				(font
					(size 1.27 1.27)
				)
			)
		)
		(duplicate_pad_numbers_are_jumpers no)
		(fp_line
			(start 0.7874 0.4064)
			(end -0.7874 0.4064)
			(stroke
				(width 0.1524)
				(type default)
			)
			(layer "F.SilkS")
		)
		(fp_line
			(start 0.7874 -0.4064)
			(end 0.7874 0.4064)
			(stroke
				(width 0.1524)
				(type default)
			)
			(layer "F.SilkS")
		)
		(fp_line
			(start -0.7874 0.4064)
			(end -0.7874 -0.4064)
			(stroke
				(width 0.1524)
				(type default)
			)
			(layer "F.SilkS")
		)
		(fp_line
			(start -0.7874 -0.4064)
			(end 0.7874 -0.4064)
			(stroke
				(width 0.1524)
				(type default)
			)
			(layer "F.SilkS")
		)
		(fp_line
			(start 0.67945 0.3048)
			(end 0.120396 0.3048)
			(stroke
				(width 0.1)
				(type default)
			)
			(layer "F.Fab")
		)
		(fp_line
			(start 0.67945 -0.3048)
			(end 0.67945 0.3048)
			(stroke
				(width 0.1)
				(type default)
			)
			(layer "F.Fab")
		)
		(fp_line
			(start 0.12065 -0.2794)
			(end 0.12065 -0.3048)
			(stroke
				(width 0.1)
				(type default)
			)
			(layer "F.Fab")
		)
		(fp_line
			(start 0.12065 -0.3048)
			(end 0.67945 -0.3048)
			(stroke
				(width 0.1)
				(type default)
			)
			(layer "F.Fab")
		)
		(fp_line
			(start 0.120396 0.3048)
			(end 0.120396 0.2794)
			(stroke
				(width 0.1)
				(type default)
			)
			(layer "F.Fab")
		)
		(fp_line
			(start 0.120396 0.2794)
			(end -0.12065 0.2794)
			(stroke
				(width 0.1)
				(type default)
			)
			(layer "F.Fab")
		)
		(fp_line
			(start -0.12065 0.3048)
			(end -0.67945 0.3048)
			(stroke
				(width 0.1)
				(type default)
			)
			(layer "F.Fab")
		)
		(fp_line
			(start -0.12065 0.2794)
			(end -0.12065 0.3048)
			(stroke
				(width 0.1)
				(type default)
			)
			(layer "F.Fab")
		)
		(fp_line
			(start -0.12065 -0.2794)
			(end 0.12065 -0.2794)
			(stroke
				(width 0.1)
				(type default)
			)
			(layer "F.Fab")
		)
		(fp_line
			(start -0.12065 -0.305054)
			(end -0.12065 -0.2794)
			(stroke
				(width 0.1)
				(type default)
			)
			(layer "F.Fab")
		)
		(fp_line
			(start -0.67945 0.3048)
			(end -0.67945 -0.305054)
			(stroke
				(width 0.1)
				(type default)
			)
			(layer "F.Fab")
		)
		(fp_line
			(start -0.67945 -0.305054)
			(end -0.12065 -0.305054)
			(stroke
				(width 0.1)
				(type default)
			)
			(layer "F.Fab")
		)
		(pad "1" smd circle
			(at -0.40005 0 180)
			(size 0 0)
			(layers "F.Cu" "F.Mask" "F.Paste")
			(net "P3V3_AUX")
		)
		(pad "2" smd circle
			(at 0.40005 0 180)
			(size 0 0)
			(layers "F.Cu" "F.Mask" "F.Paste")
			(net "PCA9552_MB1_A1")
		)
	)
	(footprint ""
		(layer "F.Cu")
		(at 5.461 -188.214)
		(property "Reference" "R311"
			(at 0 0 0)
			(layer "F.SilkS")
			(hide yes)
			(effects
				(font
					(size 1.27 1.27)
				)
			)
		)
		(property "Value" ""
			(at 0 0 0)
			(layer "F.Fab")
			(effects
				(font
					(size 1.27 1.27)
				)
			)
		)
		(duplicate_pad_numbers_are_jumpers no)
		(fp_line
			(start -0.7874 -0.4064)
			(end 0.7874 -0.4064)
			(stroke
				(width 0.1524)
				(type default)
			)
			(layer "F.SilkS")
		)
		(fp_line
			(start -0.7874 0.4064)
			(end -0.7874 -0.4064)
			(stroke
				(width 0.1524)
				(type default)
			)
			(layer "F.SilkS")
		)
		(fp_line
			(start 0.7874 -0.4064)
			(end 0.7874 0.4064)
			(stroke
				(width 0.1524)
				(type default)
			)
			(layer "F.SilkS")
		)
		(fp_line
			(start 0.7874 0.4064)
			(end -0.7874 0.4064)
			(stroke
				(width 0.1524)
				(type default)
			)
			(layer "F.SilkS")
		)
		(fp_line
			(start -0.67945 -0.305054)
			(end -0.12065 -0.305054)
			(stroke
				(width 0.1)
				(type default)
			)
			(layer "F.Fab")
		)
		(fp_line
			(start -0.67945 0.3048)
			(end -0.67945 -0.305054)
			(stroke
				(width 0.1)
				(type default)
			)
			(layer "F.Fab")
		)
		(fp_line
			(start -0.12065 -0.305054)
			(end -0.12065 -0.2794)
			(stroke
				(width 0.1)
				(type default)
			)
			(layer "F.Fab")
		)
		(fp_line
			(start -0.12065 -0.2794)
			(end 0.12065 -0.2794)
			(stroke
				(width 0.1)
				(type default)
			)
			(layer "F.Fab")
		)
		(fp_line
			(start -0.12065 0.2794)
			(end -0.12065 0.3048)
			(stroke
				(width 0.1)
				(type default)
			)
			(layer "F.Fab")
		)
		(fp_line
			(start -0.12065 0.3048)
			(end -0.67945 0.3048)
			(stroke
				(width 0.1)
				(type default)
			)
			(layer "F.Fab")
		)
		(fp_line
			(start 0.120396 0.2794)
			(end -0.12065 0.2794)
			(stroke
				(width 0.1)
				(type default)
			)
			(layer "F.Fab")
		)
		(fp_line
			(start 0.120396 0.3048)
			(end 0.120396 0.2794)
			(stroke
				(width 0.1)
				(type default)
			)
			(layer "F.Fab")
		)
		(fp_line
			(start 0.12065 -0.3048)
			(end 0.67945 -0.3048)
			(stroke
				(width 0.1)
				(type default)
			)
			(layer "F.Fab")
		)
		(fp_line
			(start 0.12065 -0.2794)
			(end 0.12065 -0.3048)
			(stroke
				(width 0.1)
				(type default)
			)
			(layer "F.Fab")
		)
		(fp_line
			(start 0.67945 -0.3048)
			(end 0.67945 0.3048)
			(stroke
				(width 0.1)
				(type default)
			)
			(layer "F.Fab")
		)
		(fp_line
			(start 0.67945 0.3048)
			(end 0.120396 0.3048)
			(stroke
				(width 0.1)
				(type default)
			)
			(layer "F.Fab")
		)
		(pad "1" smd circle
			(at -0.40005 0)
			(size 0 0)
			(layers "F.Cu" "F.Mask" "F.Paste")
			(net "P3V3_AUX")
		)
		(pad "2" smd circle
			(at 0.40005 0)
			(size 0 0)
			(layers "F.Cu" "F.Mask" "F.Paste")
			(net "FRU_ADDR1")
		)
	)
	(footprint ""
		(layer "F.Cu")
		(at 42.40784 -331.27442)
		(property "Reference" ""
			(at 0 0 0)
			(layer "F.SilkS")
			(hide yes)
			(effects
				(font
					(size 1.27 1.27)
				)
			)
		)
		(property "Value" ""
			(at 0 0 0)
			(layer "F.Fab")
			(effects
				(font
					(size 1.27 1.27)
				)
			)
		)
		(duplicate_pad_numbers_are_jumpers no)
		(pad "1" smd circle
			(at 0 0)
			(size 0.9906 0.9906)
			(layers "F.Cu" "F.Mask" "F.Paste")
			(net "Net_595")
		)
		(zone
			(layer "F.Cu")
			(hatch none 0.5)
			(connect_pads
				(clearance 0)
			)
			(min_thickness 0.25)
			(keepout
				(tracks not_allowed)
				(vias allowed)
				(pads allowed)
				(copperpour not_allowed)
				(footprints allowed)
			)
			(placement
				(enabled no)
				(sheetname "")
			)
			(fill
				(thermal_gap 0.5)
				(thermal_bridge_width 0.5)
				(island_removal_mode 0)
			)
			(polygon
				(pts
					(arc
						(start 44.03344 -331.27442)
						(mid 40.78224 -331.27442)
						(end 44.03344 -331.27442)
					)
				)
			)
		)
	)
)
